# S9S_MB_2U (Grand Teton) — schematic netlist excerpt (pin names and nets, part order shuffled) for the footprints in the layout excerpt that follows; sources: Cadence DE-HDL packaged netlist, KiCad conversion of 03242023_DA0F0TMBIJ0_F0T_Motherboard_J_brd_V01_OCP.brd

R4143  Q_RES  33.2 1% CHIP  pkg 0402LF  page 215 : A = GPU_3V3IO_RSVD0_FFU_ISO ; B = GPU_3V3IO_RSVD0_FFU_ISO_R
C2460  Q_CAP  1000PF 50V 5% X7R  pkg 0402  page 299 : A = PWRGD_PVPP_HBM_CPU1_R ; B = GND

(kicad_pcb
	(version 20260206)
	(generator "pcbnew")
	(generator_version "10.0")
	(general
		(thickness 1.6)
		(legacy_teardrops no)
	)
	(paper "A4")
	(title_block
		(title "03242023_DA0F0TMBIJ0_F0T_Motherboard_J_brd_V01_OCP.brd")
		(comment 1 "Grand Teton / footprints 1592-1593 of 6105")
	)
	(layers
		(0 "F.Cu" signal "TOP")
		(4 "In1.Cu" signal "GND")
		(6 "In2.Cu" signal "IN1")
		(8 "In3.Cu" signal "GND1")
		(10 "In4.Cu" signal "IN2")
		(12 "In5.Cu" signal "GND2")
		(14 "In6.Cu" signal "IN3")
		(16 "In7.Cu" signal "GND3")
		(18 "In8.Cu" signal "VCC")
		(20 "In9.Cu" signal "VCC1")
		(22 "In10.Cu" signal "GND4")
		(24 "In11.Cu" signal "IN4")
		(26 "In12.Cu" signal "GND5")
		(28 "In13.Cu" signal "IN5")
		(30 "In14.Cu" signal "GND6")
		(32 "In15.Cu" signal "IN6")
		(34 "In16.Cu" signal "GND7")
		(2 "B.Cu" signal "BOTTOM")
		(9 "F.Adhes" user "F.Adhesive")
		(11 "B.Adhes" user "B.Adhesive")
		(13 "F.Paste" user "Package Geometry/Pastemask Top")
		(15 "B.Paste" user "Package Geometry/Pastemask Bottom")
		(5 "F.SilkS" user "Ref Des/Silkscreen Top")
		(7 "B.SilkS" user "Ref Des/Silkscreen Bottom")
		(1 "F.Mask" user "Board Geometry/Soldermask Top")
		(3 "B.Mask" user "Board Geometry/Soldermask Bottom")
		(17 "Dwgs.User" user "User.Drawings")
		(19 "Cmts.User" user "User.Comments")
		(21 "Eco1.User" user "User.Eco1")
		(23 "Eco2.User" user "User.Eco2")
		(25 "Edge.Cuts" user "Board Geometry/Outline")
		(27 "Margin" user)
		(31 "F.CrtYd" user "Package Geometry/Place Bound Top")
		(29 "B.CrtYd" user "Package Geometry/Place Bound Bottom")
		(35 "F.Fab" user "Ref Des/Assembly Top")
		(33 "B.Fab" user "Ref Des/Assembly Bottom")
	)
	(footprint ""
		(layer "F.Cu")
		(at 119.341138 -355.71049 180)
		(property "Reference" "C2460"
			(at 0 0 180)
			(layer "F.SilkS")
			(hide yes)
			(effects
				(font
					(size 1.27 1.27)
				)
			)
		)
		(property "Value" ""
			(at 0 0 180)
			(layer "F.Fab")
			(effects
				(font
					(size 1.27 1.27)
				)
			)
		)
		(duplicate_pad_numbers_are_jumpers no)
		(fp_line
			(start 0.7874 0.4064)
			(end -0.7874 0.4064)
			(stroke
				(width 0.1524)
				(type default)
			)
			(layer "F.SilkS")
		)
		(fp_line
			(start 0.7874 -0.4064)
			(end 0.7874 0.4064)
			(stroke
				(width 0.1524)
				(type default)
			)
			(layer "F.SilkS")
		)
		(fp_line
			(start -0.7874 0.4064)
			(end -0.7874 -0.4064)
			(stroke
				(width 0.1524)
				(type default)
			)
			(layer "F.SilkS")
		)
		(fp_line
			(start -0.7874 -0.4064)
			(end 0.7874 -0.4064)
			(stroke
				(width 0.1524)
				(type default)
			)
			(layer "F.SilkS")
		)
		(fp_line
			(start 0.67945 0.3048)
			(end 0.120396 0.3048)
			(stroke
				(width 0.1)
				(type default)
			)
			(layer "F.Fab")
		)
		(fp_line
			(start 0.67945 -0.3048)
			(end 0.67945 0.3048)
			(stroke
				(width 0.1)
				(type default)
			)
			(layer "F.Fab")
		)
		(fp_line
			(start 0.12065 -0.2794)
			(end 0.12065 -0.3048)
			(stroke
				(width 0.1)
				(type default)
			)
			(layer "F.Fab")
		)
		(fp_line
			(start 0.12065 -0.3048)
			(end 0.67945 -0.3048)
			(stroke
				(width 0.1)
				(type default)
			)
			(layer "F.Fab")
		)
		(fp_line
			(start 0.120396 0.3048)
			(end 0.120396 0.2794)
			(stroke
				(width 0.1)
				(type default)
			)
			(layer "F.Fab")
		)
		(fp_line
			(start 0.120396 0.2794)
			(end -0.12065 0.2794)
			(stroke
				(width 0.1)
				(type default)
			)
			(layer "F.Fab")
		)
		(fp_line
			(start -0.12065 0.3048)
			(end -0.67945 0.3048)
			(stroke
				(width 0.1)
				(type default)
			)
			(layer "F.Fab")
		)
		(fp_line
			(start -0.12065 0.2794)
			(end -0.12065 0.3048)
			(stroke
				(width 0.1)
				(type default)
			)
			(layer "F.Fab")
		)
		(fp_line
			(start -0.12065 -0.2794)
			(end 0.12065 -0.2794)
			(stroke
				(width 0.1)
				(type default)
			)
			(layer "F.Fab")
		)
		(fp_line
			(start -0.12065 -0.305054)
			(end -0.12065 -0.2794)
			(stroke
				(width 0.1)
				(type default)
			)
			(layer "F.Fab")
		)
		(fp_line
			(start -0.67945 0.3048)
			(end -0.67945 -0.305054)
			(stroke
				(width 0.1)
				(type default)
			)
			(layer "F.Fab")
		)
		(fp_line
			(start -0.67945 -0.305054)
			(end -0.12065 -0.305054)
			(stroke
				(width 0.1)
				(type default)
			)
			(layer "F.Fab")
		)
		(pad "1" smd circle
			(at -0.40005 0 180)
			(size 0 0)
			(layers "F.Cu" "F.Mask" "F.Paste")
			(net "PWRGD_PVPP_HBM_CPU1_R")
		)
		(pad "2" smd circle
			(at 0.40005 0 180)
			(size 0 0)
			(layers "F.Cu" "F.Mask" "F.Paste")
			(net "GND")
		)
	)
	(footprint ""
		(layer "F.Cu")
		(at 204.93736 -115.534948 180)
		(property "Reference" "R4143"
			(at 0 0 180)
			(layer "F.SilkS")
			(hide yes)
			(effects
				(font
					(size 1.27 1.27)
				)
			)
		)
		(property "Value" ""
			(at 0 0 180)
			(layer "F.Fab")
			(effects
				(font
					(size 1.27 1.27)
				)
			)
		)
		(duplicate_pad_numbers_are_jumpers no)
		(fp_line
			(start 0.7874 0.4064)
			(end -0.7874 0.4064)
			(stroke
				(width 0.1524)
				(type default)
			)
			(layer "F.SilkS")
		)
		(fp_line
			(start 0.7874 -0.4064)
			(end 0.7874 0.4064)
			(stroke
				(width 0.1524)
				(type default)
			)
			(layer "F.SilkS")
		)
		(fp_line
			(start -0.7874 0.4064)
			(end -0.7874 -0.4064)
			(stroke
				(width 0.1524)
				(type default)
			)
			(layer "F.SilkS")
		)
		(fp_line
			(start -0.7874 -0.4064)
			(end 0.7874 -0.4064)
			(stroke
				(width 0.1524)
				(type default)
			)
			(layer "F.SilkS")
		)
		(fp_line
			(start 0.67945 0.3048)
			(end 0.120396 0.3048)
			(stroke
				(width 0.1)
				(type default)
			)
			(layer "F.Fab")
		)
		(fp_line
			(start 0.67945 -0.3048)
			(end 0.67945 0.3048)
			(stroke
				(width 0.1)
				(type default)
			)
			(layer "F.Fab")
		)
		(fp_line
			(start 0.12065 -0.2794)
			(end 0.12065 -0.3048)
			(stroke
				(width 0.1)
				(type default)
			)
			(layer "F.Fab")
		)
		(fp_line
			(start 0.12065 -0.3048)
			(end 0.67945 -0.3048)
			(stroke
				(width 0.1)
				(type default)
			)
			(layer "F.Fab")
		)
		(fp_line
			(start 0.120396 0.3048)
			(end 0.120396 0.2794)
			(stroke
				(width 0.1)
				(type default)
			)
			(layer "F.Fab")
		)
		(fp_line
			(start 0.120396 0.2794)
			(end -0.12065 0.2794)
			(stroke
				(width 0.1)
				(type default)
			)
			(layer "F.Fab")
		)
		(fp_line
			(start -0.12065 0.3048)
			(end -0.67945 0.3048)
			(stroke
				(width 0.1)
				(type default)
			)
			(layer "F.Fab")
		)
		(fp_line
			(start -0.12065 0.2794)
			(end -0.12065 0.3048)
			(stroke
				(width 0.1)
				(type default)
			)
			(layer "F.Fab")
		)
		(fp_line
			(start -0.12065 -0.2794)
			(end 0.12065 -0.2794)
			(stroke
				(width 0.1)
				(type default)
			)
			(layer "F.Fab")
		)
		(fp_line
			(start -0.12065 -0.305054)
			(end -0.12065 -0.2794)
			(stroke
				(width 0.1)
				(type default)
			)
			(layer "F.Fab")
		)
		(fp_line
			(start -0.67945 0.3048)
			(end -0.67945 -0.305054)
			(stroke
				(width 0.1)
				(type default)
			)
			(layer "F.Fab")
		)
		(fp_line
			(start -0.67945 -0.305054)
			(end -0.12065 -0.305054)
			(stroke
				(width 0.1)
				(type default)
			)
			(layer "F.Fab")
		)
		(pad "1" smd circle
			(at -0.40005 0 180)
			(size 0 0)
			(layers "F.Cu" "F.Mask" "F.Paste")
			(net "GPU_3V3IO_RSVD0_FFU_ISO")
		)
		(pad "2" smd circle
			(at 0.40005 0 180)
			(size 0 0)
			(layers "F.Cu" "F.Mask" "F.Paste")
			(net "GPU_3V3IO_RSVD0_FFU_ISO_R")
		)
	)
)
